FILE_TYPE = CONNECTIVITY;
{Allegro Design Entry HDL 17.2-2016 S081 (4005846) 1/11/2022}
"PAGE_NUMBER" = 194;
0"NC";
1"GND\g";
2"GND\g";
3"GND\g";
4"GND\g";
5"GND\g";
6"GND\g";
7"GND\g";
8"GND\g";
9"GND\g";
10"GND\g";
11"SW_PVDDCR_CPU1_P1_BOOT3_R";
12"GND\g";
13"SW_PVDDCR_CPU1_P1_SW3";
14"SW_PVDDCR_CPU1_P1_BOOTR3";
15"SW_PVDDCR_CPU1_P1_BOOTR4";
16"SW_PVDDCR_CPU1_P1_SW4";
17"PVDDCR_CPU1_P1_VCC4";
18"PVDDCR_CPU1_P1_PVCC\g";
19"PVDDCR_CPU1_P1_VCCS"CDS_PHYS_NET_NAME"PVCCIN_CPU0_VREF";
20"PVDDCR_CPU1_P1_LSET4";
21"PVDDCR_CPU1_P1_PWM3";
22"PVDDCR_CPU1_P1_TEMP0";
23"PVDDCR_CPU1_P1_TEMP0";
24"PVDDCR_CPU1_P1_PWM4";
25"PVDDCR_CPU1_P1_IMON4";
26"NC_PVDDCR_CPU1_P1_DNC4";
27"GND\g";
28"SW_P12V_STBY_PVDDCR_CPU1_P1_FLT\g";
29"GND\g";
30"PVDDCR_CPU1_P1_PVCC\g";
31"PVDDCR_CPU1_P1_LSET3";
32"PVDDCR_CPU1_P1_VCC3";
33"PVDDCR_CPU1_P1_VCCS"CDS_PHYS_NET_NAME"PVCCIN_CPU0_VREF";
34"PVDDCR_CPU1_P1_IMON3";
35"NC_PVDDCR_CPU1_P1_DNC3";
36"SW_P12V_STBY_PVDDCR_CPU1_P1_FLT\g";
37"NC_PVDDCR_CPU1_P1_GL2_3";
38"NC_PVDDCR_CPU1_P1_GL1_3";
39"SW_PVDDCR_CPU1_P1_BOOT3";
40"SW_PVDDCR_CPU1_P1_BOOT4";
41"NC_PVDDCR_CPU1_P1_GL1_4";
42"NC_PVDDCR_CPU1_P1_GL2_4";
43"GND\g";
44"SW_PVDDCR_CPU1_P1_SW4_RC";
45"PVDDCR_CPU1_P1_VOS4";
46"SW_PVDDCR_CPU1_P1_BOOT4_R";
47"IND_CPU1_P1_CPL3";
48"PVDDCR_CPU1_P1\g";
49"GND\g";
50"PVDDCR_CPU1_P1_VOS3";
51"SW_PVDDCR_CPU1_P1_SW3_RC";
52"PVDDCR_CPU1_P1\g";
53"IND_CPU1_P1_CPL2";
54"IND_CPU1_P1_CPL3";
55"GND\g";
56"GND\g";
%"UNIVERSAL_GND"
"1","(1300,875)","0","pure_quanta_power","I1";
;
CDS_LIB"pure_quanta_power"
HDL_POWER"GND";
"A"1;
%"Q_CAP"
"1","(800,1225)","0","pure_quanta","I100";
;
LOCATION"PC403_4"
$SEC"1"
CDS_SEC"1"
MATERIAL"X7R"
TOLERANCE"10%"
VALUE"0.1UF"
PART_NUMBER"CH4104K1B00"
VOLTAGE"25V"
PACK_TYPE"0402"
CDS_LIB"pure_quanta";
"B"
$PN"2"8;
"A"
$PN"1"19;
%"Q_CAP"
"1","(5600,4650)","0","pure_quanta","I101";
;
LOCATION"PC414"
$SEC"1"
CDS_SEC"1"
MATERIAL"X7R"
TOLERANCE"10%"
VALUE"0.22UF"
PART_NUMBER"CH4223K1B00"
VOLTAGE"16V"
PACK_TYPE"0402"
CDS_LIB"pure_quanta";
"B"
$PN"2"14;
"A"
$PN"1"11;
%"Q_RES"
"1","(4625,4775)","0","pure_quanta","I102";
;
LOCATION"PR267"
$SEC"1"
CDS_SEC"1"
PACK_TYPE"0402LF"
TOLERANCE"1%"
MATERIAL"CHIP"
WATTAGE"1/16W"
VALUE"4.7"
PART_NUMBER"CS-4702FB19"
CDS_LIB"pure_quanta";
"B"
$PN"2"11;
"A"
$PN"1"39;
%"Q_CAP"
"1","(5450,1825)","0","pure_quanta","I103";
;
LOCATION"PC413"
$SEC"1"
CDS_SEC"1"
MATERIAL"X7R"
TOLERANCE"10%"
VALUE"0.22UF"
PART_NUMBER"CH4223K1B00"
VOLTAGE"16V"
PACK_TYPE"0402"
CDS_LIB"pure_quanta";
"B"
$PN"2"15;
"A"
$PN"1"46;
%"Q_RES"
"1","(4550,1950)","0","pure_quanta","I104";
;
LOCATION"PR266"
$SEC"1"
CDS_SEC"1"
PACK_TYPE"0402LF"
TOLERANCE"1%"
MATERIAL"CHIP"
WATTAGE"1/16W"
VALUE"4.7"
PART_NUMBER"CS-4702FB19"
CDS_LIB"pure_quanta";
"B"
$PN"2"46;
"A"
$PN"1"40;
%"Q_CAP"
"1","(4075,5375)","0","pure_quanta","I105";
;
LOCATION"PC406_3"
$SEC"1"
CDS_SEC"1"
MATERIAL"X7R"
TOLERANCE"10%"
VALUE"0.1UF"
PART_NUMBER"CH4104K1B00"
VOLTAGE"25V"
PACK_TYPE"0402"
CDS_LIB"pure_quanta";
"B"
$PN"2"12;
"A"
$PN"1"36;
%"Q_CAP"
"1","(4025,2525)","0","pure_quanta","I106";
;
LOCATION"PC405_4"
$SEC"1"
CDS_SEC"1"
MATERIAL"X7R"
TOLERANCE"10%"
VALUE"0.1UF"
PART_NUMBER"CH4104K1B00"
VOLTAGE"25V"
PACK_TYPE"0402"
CDS_LIB"pure_quanta";
"B"
$PN"2"43;
"A"
$PN"1"28;
%"Q_CAP"
"1","(1625,4875)","0","pure_quanta","I107";
;
LOCATION"PC400"
$SEC"1"
CDS_SEC"1"
MATERIAL"X6S"
TOLERANCE"10%"
VALUE"2.2UF"
PART_NUMBER"CH5222KEB01"
VOLTAGE"10V"
PACK_TYPE"C0402"
CDS_LIB"pure_quanta";
"B"
$PN"2"2;
"A"
$PN"1"32;
%"UNIVERSAL_GND"
"1","(1625,4675)","0","pure_quanta_power","I108";
;
CDS_LIB"pure_quanta_power"
HDL_POWER"GND";
"A"2;
%"UNIVERSAL_GND"
"1","(1975,5175)","0","pure_quanta_power","I109";
;
CDS_LIB"pure_quanta_power"
HDL_POWER"GND";
"A"3;
%"UNIVERSAL_GND"
"1","(1325,3700)","0","pure_quanta_power","I11";
;
CDS_LIB"pure_quanta_power"
HDL_POWER"GND";
"A"4;
%"Q_RES"
"2","(1625,5425)","0","pure_quanta","I110";
;
LOCATION"PR265"
$SEC"1"
CDS_SEC"1"
WATTAGE"1/16W"
MATERIAL"CHIP"
TOLERANCE"1%"
VALUE"2.2"
PART_NUMBER"CS-2202FB00"
PACK_TYPE"0402LF"
CDS_LIB"pure_quanta";
"A"
$PN"1"30;
"B"
$PN"2"32;
%"Q_CAP"
"1","(1975,5450)","0","pure_quanta","I111";
;
LOCATION"PC402_C1P1_3"
$SEC"1"
CDS_SEC"1"
MATERIAL"X6S"
TOLERANCE"10%"
VALUE"2.2UF"
PART_NUMBER"CH5222KEB01"
VOLTAGE"10V"
PACK_TYPE"C0402"
CDS_LIB"pure_quanta";
"B"
$PN"2"3;
"A"
$PN"1"30;
%"Q_CAP"
"1","(1450,2050)","0","pure_quanta","I113";
;
LOCATION"PC399"
$SEC"1"
CDS_SEC"1"
MATERIAL"X6S"
TOLERANCE"10%"
VALUE"2.2UF"
PART_NUMBER"CH5222KEB01"
VOLTAGE"10V"
PACK_TYPE"C0402"
CDS_LIB"pure_quanta";
"B"
$PN"2"5;
"A"
$PN"1"17;
%"UNIVERSAL_GND"
"1","(1450,1850)","0","pure_quanta_power","I114";
;
CDS_LIB"pure_quanta_power"
HDL_POWER"GND";
"A"5;
%"UNIVERSAL_GND"
"1","(1800,2350)","0","pure_quanta_power","I115";
;
CDS_LIB"pure_quanta_power"
HDL_POWER"GND";
"A"6;
%"Q_RES"
"2","(1450,2600)","0","pure_quanta","I116";
;
LOCATION"PR264"
$SEC"1"
CDS_SEC"1"
WATTAGE"1/16W"
MATERIAL"CHIP"
TOLERANCE"1%"
VALUE"2.2"
PART_NUMBER"CS-2202FB00"
PACK_TYPE"0402LF"
CDS_LIB"pure_quanta";
"A"
$PN"1"18;
"B"
$PN"2"17;
%"Q_CAP"
"1","(1800,2625)","0","pure_quanta","I117";
;
LOCATION"PC401_C1P1_4"
$SEC"1"
CDS_SEC"1"
MATERIAL"X6S"
TOLERANCE"10%"
VALUE"2.2UF"
PART_NUMBER"CH5222KEB01"
VOLTAGE"10V"
PACK_TYPE"C0402"
CDS_LIB"pure_quanta";
"B"
$PN"2"6;
"A"
$PN"1"18;
%"UNIVERSAL_GND"
"1","(825,3850)","0","pure_quanta_power","I119";
;
CDS_LIB"pure_quanta_power"
HDL_POWER"GND";
"A"7;
%"UNIVERSAL_GND"
"1","(800,1025)","0","pure_quanta_power","I120";
;
CDS_LIB"pure_quanta_power"
HDL_POWER"GND";
"A"8;
%"UNIVERSAL_GND"
"1","(4725,3450)","0","pure_quanta_power","I121";
;
CDS_LIB"pure_quanta_power"
HDL_POWER"GND";
"A"9;
%"Q_RES"
"2","(4725,3675)","0","pure_quanta","I122";
;
LOCATION"PR516"
$SEC"1"
CDS_SEC"1"
WATTAGE"1/8W"
MATERIAL"EMPTY"
TOLERANCE"1%"
VALUE"1.5"
PART_NUMBER"CS-1504FB00"
PACK_TYPE"0402LF"
CDS_LIB"pure_quanta";
"A"
$PN"1"51;
"B"
$PN"2"9;
%"Q_CAP"
"1","(4725,4225)","0","pure_quanta","I123";
;
LOCATION"PC206"
$SEC"1"
CDS_SEC"1"
MATERIAL"EMPTY"
TOLERANCE"10%"
VALUE"560PF"
PART_NUMBER"CH1566K1B09"
VOLTAGE"50V"
PACK_TYPE"C0402"
CDS_LIB"pure_quanta";
"B"
$PN"2"51;
"A"
$PN"1"13;
%"UNIVERSAL_GND"
"1","(4625,675)","0","pure_quanta_power","I124";
;
CDS_LIB"pure_quanta_power"
HDL_POWER"GND";
"A"10;
%"Q_RES"
"2","(4625,900)","0","pure_quanta","I125";
;
LOCATION"PR515"
$SEC"1"
CDS_SEC"1"
WATTAGE"1/8W"
MATERIAL"EMPTY"
TOLERANCE"1%"
VALUE"1.5"
PART_NUMBER"CS-1504FB00"
PACK_TYPE"0402LF"
CDS_LIB"pure_quanta";
"A"
$PN"1"44;
"B"
$PN"2"10;
%"Q_CAP"
"1","(4625,1400)","0","pure_quanta","I126";
;
LOCATION"PC205"
$SEC"1"
CDS_SEC"1"
MATERIAL"EMPTY"
TOLERANCE"10%"
VALUE"560PF"
PART_NUMBER"CH1566K1B09"
VOLTAGE"50V"
PACK_TYPE"C0402"
CDS_LIB"pure_quanta";
"B"
$PN"2"44;
"A"
$PN"1"16;
%"UNIVERSAL_GND"
"1","(7475,1250)","0","pure_quanta_power","I127";
;
CDS_LIB"pure_quanta_power"
HDL_POWER"GND";
"A"49;
%"VCC_CORE"
"1","(1625,5825)","0","pure_quanta_power","I128";
;
HDL_POWER"PVDDCR_CPU1_P1_PVCC"
CDS_LIB"pure_quanta_power";
"A"30;
%"VCC_CORE"
"1","(1450,3000)","0","pure_quanta_power","I129";
;
HDL_POWER"PVDDCR_CPU1_P1_PVCC"
CDS_LIB"pure_quanta_power";
"A"18;
%"ISL99390FRZTR5935"
"1","(3225,1600)","0","pure_quanta","I14";
;
LOCATION"PU36"
$SEC"1"
CDS_SEC"1"
PART_TYPE"SMLF"
MATERIAL"IC"
VALUE"ISL99390FRZ-TR5935"
PART_NUMBER"AL099390004"
CDS_LIB"pure_quanta"
CDS_LMAN_SYM_OUTLINE"-300,700,250,-650"
NEEDS_NO_SIZE"TRUE";
"PGND2"
$PN"7_9-20_24"27;
"GL2"
$PN"41"42;
"GL1"
$PN"6"41;
"DNC"
$PN"31"26;
"EN"
$PN"35"17;
"PGND3"
$PN"40"27;
"VOS"
$PN"1"45;
"VIN2"
$PN"30"28;
"PGND1"
$PN"5"27;
"SW"
$PN"10_19"16;
"LSET"
$PN"37"20;
"IOUT"
$PN"38"25;
"TOUT_FLT"
$PN"36"23;
"PVCC"
$PN"4"18;
"PHASE"
$PN"32"15;
"VIN1"
$PN"25_29"28;
"BOOT"
$PN"33"40;
"AGND"
$PN"2"27;
"VCC"
$PN"3"17;
"REFIN"
$PN"39"19;
"PWM"
$PN"34"24;
%"UNIVERSAL_GND"
"1","(3875,875)","0","pure_quanta_power","I15";
;
CDS_LIB"pure_quanta_power"
HDL_POWER"GND";
"A"27;
%"UNIVERSAL_GND"
"1","(3900,3700)","0","pure_quanta_power","I18";
;
CDS_LIB"pure_quanta_power"
HDL_POWER"GND";
"A"29;
%"Q_RES"
"2","(1325,3925)","2","pure_quanta","I19";
;
LOCATION"PR263"
$SEC"1"
CDS_SEC"1"
WATTAGE"1/16W"
MATERIAL"EMPTY"
TOLERANCE"1%"
VALUE"8.87K"
PART_NUMBER"CS28872FB01"
PACK_TYPE"0402LF"
CDS_LIB"pure_quanta";
"A"
$PN"1"31;
"B"
$PN"2"4;
%"Q_RES"
"2","(1300,1100)","2","pure_quanta","I2";
;
LOCATION"PR262"
$SEC"1"
CDS_SEC"1"
WATTAGE"1/16W"
MATERIAL"EMPTY"
TOLERANCE"1%"
VALUE"8.87K"
PART_NUMBER"CS28872FB01"
PACK_TYPE"0402LF"
CDS_LIB"pure_quanta";
"A"
$PN"1"20;
"B"
$PN"2"1;
%"ISL99390FRZTR5935"
"1","(3250,4425)","0","pure_quanta","I30";
;
LOCATION"PU37"
$SEC"1"
CDS_SEC"1"
PART_TYPE"SMLF"
MATERIAL"IC"
VALUE"ISL99390FRZ-TR5935"
PART_NUMBER"AL099390004"
CDS_LIB"pure_quanta"
CDS_LMAN_SYM_OUTLINE"-300,700,250,-650"
NEEDS_NO_SIZE"TRUE";
"PGND2"
$PN"7_9-20_24"29;
"GL2"
$PN"41"37;
"GL1"
$PN"6"38;
"DNC"
$PN"31"35;
"EN"
$PN"35"32;
"PGND3"
$PN"40"29;
"VOS"
$PN"1"50;
"VIN2"
$PN"30"36;
"PGND1"
$PN"5"29;
"SW"
$PN"10_19"13;
"LSET"
$PN"37"31;
"IOUT"
$PN"38"34;
"TOUT_FLT"
$PN"36"22;
"PVCC"
$PN"4"30;
"PHASE"
$PN"32"14;
"VIN1"
$PN"25_29"36;
"BOOT"
$PN"33"39;
"AGND"
$PN"2"29;
"VCC"
$PN"3"32;
"REFIN"
$PN"39"33;
"PWM"
$PN"34"21;
%"Q_CAP"
"1","(4425,2500)","0","pure_quanta","I37";
;
LOCATION"PC407_4"
$SEC"1"
CDS_SEC"1"
MATERIAL"X6S"
TOLERANCE"10%"
VALUE"1UF"
PART_NUMBER"CH5104KEB02"
VOLTAGE"25V"
PACK_TYPE"C0402"
CDS_LIB"pure_quanta";
"B"
$PN"2"43;
"A"
$PN"1"28;
%"Q_CAP"
"1","(4825,2500)","0","pure_quanta","I38";
;
LOCATION"PC409_4"
$SEC"1"
CDS_SEC"1"
MATERIAL"X6S"
TOLERANCE"10%"
VALUE"10UF"
PART_NUMBER"CH6104KEA00"
VOLTAGE"25V"
PACK_TYPE"C0805"
CDS_LIB"pure_quanta";
"B"
$PN"2"43;
"A"
$PN"1"28;
%"Q_CAP"
"1","(5225,2500)","0","pure_quanta","I40";
;
LOCATION"PC411_4"
$SEC"1"
CDS_SEC"1"
MATERIAL"X6S"
TOLERANCE"10%"
VALUE"10UF"
PART_NUMBER"CH6104KEA00"
VOLTAGE"25V"
PACK_TYPE"C0805"
CDS_LIB"pure_quanta";
"B"
$PN"2"43;
"A"
$PN"1"28;
%"UNIVERSAL_GND"
"1","(5600,2125)","0","pure_quanta_power","I41";
;
CDS_LIB"pure_quanta_power"
HDL_POWER"GND";
"A"43;
%"Q_CAP"
"1","(5600,2500)","0","pure_quanta","I42";
;
LOCATION"PC415_4"
$SEC"1"
CDS_SEC"1"
MATERIAL"X6S"
TOLERANCE"10%"
VALUE"10UF"
PART_NUMBER"CH6104KEA00"
VOLTAGE"25V"
PACK_TYPE"C0805"
CDS_LIB"pure_quanta";
"B"
$PN"2"43;
"A"
$PN"1"28;
%"VCC_CORE"
"1","(5600,2850)","0","pure_quanta_power","I43";
;
HDL_POWER"SW_P12V_STBY_PVDDCR_CPU1_P1_FLT"
CDS_LIB"pure_quanta_power";
"A"28;
%"Q_CAP"
"1","(4475,5350)","0","pure_quanta","I50";
;
LOCATION"PC408_3"
$SEC"1"
CDS_SEC"1"
MATERIAL"X6S"
TOLERANCE"10%"
VALUE"1UF"
PART_NUMBER"CH5104KEB02"
VOLTAGE"25V"
PACK_TYPE"C0402"
CDS_LIB"pure_quanta";
"B"
$PN"2"12;
"A"
$PN"1"36;
%"Q_CAP"
"1","(4875,5350)","0","pure_quanta","I51";
;
LOCATION"PC410_3"
$SEC"1"
CDS_SEC"1"
MATERIAL"X6S"
TOLERANCE"10%"
VALUE"10UF"
PART_NUMBER"CH6104KEA00"
VOLTAGE"25V"
PACK_TYPE"C0805"
CDS_LIB"pure_quanta";
"B"
$PN"2"12;
"A"
$PN"1"36;
%"Q_CAP"
"1","(5275,5350)","0","pure_quanta","I55";
;
LOCATION"PC412_3"
$SEC"1"
CDS_SEC"1"
MATERIAL"X6S"
TOLERANCE"10%"
VALUE"10UF"
VOLTAGE"25V"
PACK_TYPE"C0805"
PART_NUMBER"CH6104KEA00"
CDS_LIB"pure_quanta";
"B"
$PN"2"12;
"A"
$PN"1"36;
%"Q_CAP"
"1","(5650,5350)","0","pure_quanta","I56";
;
LOCATION"PC416_3"
$SEC"1"
CDS_SEC"1"
MATERIAL"X6S"
TOLERANCE"10%"
VALUE"10UF"
PART_NUMBER"CH6104KEA00"
VOLTAGE"25V"
PACK_TYPE"C0805"
CDS_LIB"pure_quanta";
"B"
$PN"2"12;
"A"
$PN"1"36;
%"UNIVERSAL_GND"
"1","(5650,5000)","0","pure_quanta_power","I57";
;
CDS_LIB"pure_quanta_power"
HDL_POWER"GND";
"A"12;
%"VCC_CORE"
"1","(5650,5700)","0","pure_quanta_power","I58";
;
HDL_POWER"SW_P12V_STBY_PVDDCR_CPU1_P1_FLT"
CDS_LIB"pure_quanta_power";
"A"36;
%"Q_RES"
"1","(5850,3250)","0","pure_quanta","I76";
;
LOCATION"PR269"
$SEC"1"
CDS_SEC"1"
WATTAGE"1/16W"
MATERIAL"CHIP"
TOLERANCE"5%"
VALUE"0"
PART_NUMBER"CS00002JB38"
PACK_TYPE"0402LF"
CDS_LIB"pure_quanta";
"B"
$PN"2"52;
"A"
$PN"1"50;
%"VCC_CORE"
"1","(8550,4525)","0","pure_quanta_power","I77";
;
HDL_POWER"PVDDCR_CPU1_P1"
CDS_LIB"pure_quanta_power";
"A"52;
%"Q_CAP"
"1","(8550,4225)","0","pure_quanta","I78";
;
LOCATION"PC419_3"
$SEC"1"
CDS_SEC"1"
MATERIAL"X6S"
TOLERANCE"20%"
VALUE"22UF"
PART_NUMBER"TMP_QCH622KMEA01"
VOLTAGE"4V"
PACK_TYPE"0805"
CDS_LIB"pure_quanta";
"B"
$PN"2"55;
"A"
$PN"1"52;
%"Q_CAP"
"1","(8125,4225)","0","pure_quanta","I79";
;
LOCATION"PC417_3"
$SEC"1"
CDS_SEC"1"
MATERIAL"X6S"
TOLERANCE"20%"
VALUE"22UF"
PART_NUMBER"TMP_QCH622KMEA01"
VOLTAGE"4V"
PACK_TYPE"0805"
CDS_LIB"pure_quanta";
"B"
$PN"2"55;
"A"
$PN"1"52;
%"UNIVERSAL_GND"
"1","(8550,3900)","0","pure_quanta_power","I80";
;
CDS_LIB"pure_quanta_power"
HDL_POWER"GND";
"A"55;
%"Q_RES"
"1","(5925,600)","0","pure_quanta","I92";
;
LOCATION"PR268"
$SEC"1"
CDS_SEC"1"
WATTAGE"1/16W"
MATERIAL"CHIP"
TOLERANCE"5%"
VALUE"0"
PART_NUMBER"CS00002JB38"
PACK_TYPE"0402LF"
CDS_LIB"pure_quanta";
"B"
$PN"2"48;
"A"
$PN"1"45;
%"VCC_CORE"
"1","(8700,1700)","0","pure_quanta_power","I93";
;
HDL_POWER"PVDDCR_CPU1_P1"
CDS_LIB"pure_quanta_power";
"A"48;
%"UNIVERSAL_GND"
"1","(8700,1075)","0","pure_quanta_power","I94";
;
CDS_LIB"pure_quanta_power"
HDL_POWER"GND";
"A"56;
%"Q_CAP"
"1","(8700,1400)","0","pure_quanta","I95";
;
LOCATION"PC420_4"
$SEC"1"
CDS_SEC"1"
MATERIAL"X6S"
TOLERANCE"20%"
VALUE"22UF"
PART_NUMBER"TMP_QCH622KMEA01"
VOLTAGE"4V"
PACK_TYPE"0805"
CDS_LIB"pure_quanta";
"B"
$PN"2"56;
"A"
$PN"1"48;
%"Q_CAP"
"1","(8275,1400)","0","pure_quanta","I96";
;
LOCATION"PC418_4"
$SEC"1"
CDS_SEC"1"
MATERIAL"X6S"
TOLERANCE"20%"
VALUE"22UF"
PART_NUMBER"TMP_QCH622KMEA01"
VOLTAGE"4V"
PACK_TYPE"0805"
CDS_LIB"pure_quanta";
"B"
$PN"2"56;
"A"
$PN"1"48;
%"Q_INDUCTOR4P_14"
"1","(6600,1475)","0","pure_quanta","I97";
;
LOCATION"PL43"
$SEC"1"
CDS_SEC"1"
PART_TYPE"SMLF"
MATERIAL"IND"
VALUE"150NH"
PART_NUMBER"CV+15^0TZ04"
NEEDS_NO_SIZE"TRUE"
CDS_LIB"pure_quanta";
"1"
$PN"1"16;
"4"
$PN"4"48;
"3"
$PN"3"49;
"2"
$PN"2"47;
%"Q_INDUCTOR4P_14"
"1","(6650,4300)","0","pure_quanta","I98";
;
LOCATION"PL44"
$SEC"1"
CDS_SEC"1"
PART_TYPE"SMLF"
MATERIAL"IND"
VALUE"150NH"
PART_NUMBER"CV+15^0TZ04"
NEEDS_NO_SIZE"TRUE"
CDS_LIB"pure_quanta";
"1"
$PN"1"13;
"4"
$PN"4"52;
"3"
$PN"3"54;
"2"
$PN"2"53;
%"Q_CAP"
"1","(825,4050)","0","pure_quanta","I99";
;
LOCATION"PC404_3"
$SEC"1"
CDS_SEC"1"
MATERIAL"X7R"
TOLERANCE"10%"
VALUE"0.1UF"
PART_NUMBER"CH4104K1B00"
VOLTAGE"25V"
PACK_TYPE"0402"
CDS_LIB"pure_quanta";
"B"
$PN"2"7;
"A"
$PN"1"33;
END.
